# T6G (Grand Teton) — schematic netlist excerpt (pin names and nets, part order shuffled) for the footprints in the layout excerpt that follows; sources: Cadence DE-HDL packaged netlist, KiCad conversion of 04192023_DAF0TMB3IC0_F0TG_MB_C_brd_V02_OCP.brd

J18  SCONN288_DDR506112002KQ  IO  pkg DDR288S_1-1VXC  page 94
  VIN_BULK0  = P12V_MEM_CPU0
  RFU0  = NC
  VIN_MGMT  = P3V3_AUX
  HSCL  = I3C_SPD_DDRI_CPU0_SCL
  HSDA  = I3C_SPD_DDRI_CPU0_SDA
  VSS0  = GND
  DQ0_A  = M_I_CPU0_SA_DQ<0>
  VSS1  = GND
  DQ1_A  = M_I_CPU0_SA_DQ<1>
  VSS2  = GND
  DQS0_A_T  = M_I_CPU0_SA_DQS_DP<0>
  DQS0_A_C  = M_I_CPU0_SA_DQS_DN<0>
  VSS3  = GND
  DQ4_A  = M_I_CPU0_SA_DQ<4>
  VSS4  = GND
  DQ5_A  = M_I_CPU0_SA_DQ<5>
  VSS5  = GND
  DQ8_A  = M_I_CPU0_SA_DQ<8>
  VSS6  = GND
  DQ9_A  = M_I_CPU0_SA_DQ<9>
  VSS7  = GND
  DQS1_A_T  = M_I_CPU0_SA_DQS_DP<1>
  DQS1_A_C  = M_I_CPU0_SA_DQS_DN<1>
  VSS8  = GND
  DQ12_A  = M_I_CPU0_SA_DQ<12>
  VSS9  = GND
  DQ13_A  = M_I_CPU0_SA_DQ<13>
  VSS10  = GND
  DQ16_A  = M_I_CPU0_SA_DQ<16>
  VSS11  = GND
  DQ17_A  = M_I_CPU0_SA_DQ<17>
  VSS12  = GND
  DQS2_A_T  = M_I_CPU0_SA_DQS_DP<2>
  DQS2_A_C  = M_I_CPU0_SA_DQS_DN<2>
  VSS13  = GND
  DQ20_A  = M_I_CPU0_SA_DQ<20>
  VSS14  = GND
  DQ21_A  = M_I_CPU0_SA_DQ<21>
  VSS15  = GND
  DQ24_A  = M_I_CPU0_SA_DQ<24>
  VSS16  = GND
  DQ25_A  = M_I_CPU0_SA_DQ<25>
  VSS17  = GND
  DQS3_A_T  = M_I_CPU0_SA_DQS_DP<3>
  DQS3_A_C  = M_I_CPU0_SA_DQS_DN<3>
  VSS18  = GND
  DQ28_A  = M_I_CPU0_SA_DQ<28>
  VSS19  = GND
  DQ29_A  = M_I_CPU0_SA_DQ<29>
  VSS20  = GND
  CB0_A  = M_I_CPU0_SA_CB<0>
  VSS21  = GND
  CB1_A  = M_I_CPU0_SA_CB<1>
  VSS22  = GND
  DQS4_A_T  = M_I_CPU0_SA_DQS_DP<4>
  DQS4_A_C  = M_I_CPU0_SA_DQS_DN<4>
  VSS23  = GND
  CB4_A  = M_I_CPU0_SA_CB<4>
  VSS24  = GND
  CB5_A  = M_I_CPU0_SA_CB<5>
  VSS25  = GND
  ALERT_N  = M_I_CPU0_ALERT_N
  VSS26  = GND
  CS0_A_N  = M_I_CPU0_SA_CS_N<0>
  VSS27  = GND
  CA0_A  = M_I_CPU0_SA_CA<0>
  VSS28  = GND
  CA2_A  = M_I_CPU0_SA_CA<2>
  VSS29  = GND
  CA4_A  = M_I_CPU0_SA_CA<4>
  VSS30  = GND
  CA6_A  = M_I_CPU0_SA_CA<6>
  VSS31  = GND
  PAR_A  = M_I_CPU0_SA_PAR
  VSS32  = GND
  CA0_B  = M_I_CPU0_SB_CA<0>
  VSS33  = GND
  CA2_B  = M_I_CPU0_SB_CA<2>
  VSS34  = GND
  CA4_B  = M_I_CPU0_SB_CA<4>
  VSS35  = GND
  CA6_B  = M_I_CPU0_SB_CA<6>
  VSS36  = GND
  CS0_B_N  = M_I_CPU0_SB_CS_N<0>
  VSS37  = GND
  \lbd||rsp_a_n\  = M_I_CPU0_SA_RSP<0>
  \lbs||rsp_b_n\  = M_I_CPU0_SB_RSP<0>
  VSS38  = GND
  CB4_B  = M_I_CPU0_SB_CB<4>
  VSS39  = GND
  CB5_B  = M_I_CPU0_SB_CB<5>
  VSS40  = GND
  \dqs9_b_t||tdqs9_b_t||dbi4_b_n\  = M_I_CPU0_SB_DQS_DP<9>
  \dqs9_b_c||tdqs9_b_c\  = M_I_CPU0_SB_DQS_DN<9>
  VSS41  = GND
  CB0_B  = M_I_CPU0_SB_CB<0>
  VSS42  = GND
  CB1_B  = M_I_CPU0_SB_CB<1>
  VSS43  = GND
  DQ0_B  = M_I_CPU0_SB_DQ<0>
  VSS44  = GND
  DQ1_B  = M_I_CPU0_SB_DQ<1>
  VSS45  = GND
  DQS0_B_T  = M_I_CPU0_SB_DQS_DP<0>
  DQS0_B_C  = M_I_CPU0_SB_DQS_DN<0>
  VSS46  = GND
  DQ4_B  = M_I_CPU0_SB_DQ<4>
  VSS47  = GND
  DQ5_B  = M_I_CPU0_SB_DQ<5>
  VSS48  = GND
  DQ8_B  = M_I_CPU0_SB_DQ<8>
  VSS49  = GND
  DQ9_B  = M_I_CPU0_SB_DQ<9>
  VSS50  = GND
  DQS1_B_T  = M_I_CPU0_SB_DQS_DP<1>
  DQS1_B_C  = M_I_CPU0_SB_DQS_DN<1>
  VSS51  = GND
  DQ12_B  = M_I_CPU0_SB_DQ<12>
  VSS52  = GND
  DQ13_B  = M_I_CPU0_SB_DQ<13>
  VSS53  = GND
  DQ16_B  = M_I_CPU0_SB_DQ<16>
  VSS54  = GND
  DQ17_B  = M_I_CPU0_SB_DQ<17>
  VSS55  = GND
  DQS2_B_T  = M_I_CPU0_SB_DQS_DP<2>
  DQS2_B_C  = M_I_CPU0_SB_DQS_DN<2>
  VSS56  = GND
  DQ20_B  = M_I_CPU0_SB_DQ<20>
  VSS57  = GND
  DQ21_B  = M_I_CPU0_SB_DQ<21>
  VSS58  = GND
  DQ24_B  = M_I_CPU0_SB_DQ<24>
  VSS59  = GND
  DQ25_B  = M_I_CPU0_SB_DQ<25>
  VSS60  = GND
  DQS3_B_T  = M_I_CPU0_SB_DQS_DP<3>
  DQS3_B_C  = M_I_CPU0_SB_DQS_DN<3>
  VSS61  = GND
  DQ28_B  = M_I_CPU0_SB_DQ<28>
  VSS62  = GND
  DQ29_B  = M_I_CPU0_SB_DQ<29>
  VSS63  = GND
  RFU1  = NC
  VIN_BULK1  = P12V_MEM_CPU0
  VIN_BULK2  = P12V_MEM_CPU0
  \pwr_good||fail_n\  = PWRGD_CHI_CPU0_DIMM
  HAS  = PD_CHI_CPU0_DIMM_SAA
  RFU2  = NC
  RFU3  = NC
  VSS64  = GND
  DQ2_A  = M_I_CPU0_SA_DQ<2>
  VSS65  = GND
  DQ3_A  = M_I_CPU0_SA_DQ<3>
  VSS66  = GND
  \dqs5_a_c||tdqs5_a_c||dqs5_a_t||tdqs5_a_t\  = M_I_CPU0_SA_DQS_DN<5>
  \dqs5_a_t||tdqs5_a_t\  = M_I_CPU0_SA_DQS_DP<5>
  VSS67  = GND
  DQ6_A  = M_I_CPU0_SA_DQ<6>
  VSS68  = GND
  DQ7_A  = M_I_CPU0_SA_DQ<7>
  VSS69  = GND
  DQ10_A  = M_I_CPU0_SA_DQ<10>
  VSS70  = GND
  DQ11_A  = M_I_CPU0_SA_DQ<11>
  VSS71  = GND
  \dqs6_a_c||tdqs6_a_c||dqs6_a_t||tdqs6_a_t\  = M_I_CPU0_SA_DQS_DN<6>
  \dqs6_a_t||tdqs6_a_t\  = M_I_CPU0_SA_DQS_DP<6>
  VSS72  = GND
  DQ14_A  = M_I_CPU0_SA_DQ<14>
  VSS73  = GND
  DQ15_A  = M_I_CPU0_SA_DQ<15>
  VSS74  = GND
  DQ18_A  = M_I_CPU0_SA_DQ<18>
  VSS75  = GND
  DQ19_A  = M_I_CPU0_SA_DQ<19>
  VSS76  = GND
  \dqs7_a_c||tdqs7_a_c\  = M_I_CPU0_SA_DQS_DN<7>
  \dqs7_a_t||tdqs7_a_t\  = M_I_CPU0_SA_DQS_DP<7>
  VSS77  = GND
  DQ22_A  = M_I_CPU0_SA_DQ<22>
  VSS78  = GND
  DQ23_A  = M_I_CPU0_SA_DQ<23>
  VSS79  = GND
  DQ26_A  = M_I_CPU0_SA_DQ<26>
  VSS80  = GND
  DQ27_A  = M_I_CPU0_SA_DQ<27>
  VSS81  = GND
  \dqs8_a_c||tdqs8_a_c\  = M_I_CPU0_SA_DQS_DN<8>
  \dqs8_a_t||tdqs8_a_t\  = M_I_CPU0_SA_DQS_DP<8>
  VSS82  = GND
  DQ30_A  = M_I_CPU0_SA_DQ<30>
  VSS83  = GND
  DQ31_A  = M_I_CPU0_SA_DQ<31>
  VSS84  = GND
  CB2_A  = M_I_CPU0_SA_CB<2>
  VSS85  = GND
  CB3_A  = M_I_CPU0_SA_CB<3>
  VSS86  = GND
  \dqs9_a_c||tdqs9_a_c\  = M_I_CPU0_SA_DQS_DN<9>
  \dqs9_a_t||tdqs9_a_t\  = M_I_CPU0_SA_DQS_DP<9>
  VSS87  = GND
  CB6_A  = M_I_CPU0_SA_CB<6>
  VSS88  = GND
  CB7_A  = M_I_CPU0_SA_CB<7>
  VSS89  = GND
  RESET_N  = M_I_CPU0_RESET_N
  VSS90  = GND
  CS1_A_N  = M_I_CPU0_SA_CS_N<1>
  VSS91  = GND
  CA1_A  = M_I_CPU0_SA_CA<1>
  VSS92  = GND
  CA3_A  = M_I_CPU0_SA_CA<3>
  VSS93  = GND
  CA5_A  = M_I_CPU0_SA_CA<5>
  VSS94  = GND
  CK_T  = M_I_CPU0_CLK_DP<0>
  CK_C  = M_I_CPU0_CLK_DN<0>
  VSS95  = GND
  RFU4  = NC
  CA1_B  = M_I_CPU0_SB_CA<1>
  VSS96  = GND
  CA3_B  = M_I_CPU0_SB_CA<3>
  VSS97  = GND
  CA5_B  = M_I_CPU0_SB_CA<5>
  VSS98  = GND
  PAR_B  = M_I_CPU0_SB_PAR
  VSS99  = GND
  CS1_B_N  = M_I_CPU0_SB_CS_N<1>
  VSS100  = GND
  RFU5  = NC
  RFU6  = NC
  VSS101  = GND
  CB6_B  = M_I_CPU0_SB_CB<6>
  VSS102  = GND
  CB7_B  = M_I_CPU0_SB_CB<7>
  VSS103  = GND
  DQS4_B_C  = M_I_CPU0_SB_DQS_DN<4>
  DQS4_B_T  = M_I_CPU0_SB_DQS_DP<4>
  VSS104  = GND
  CB2_B  = M_I_CPU0_SB_CB<2>
  VSS105  = GND
  CB3_B  = M_I_CPU0_SB_CB<3>
  VSS106  = GND
  DQ2_B  = M_I_CPU0_SB_DQ<2>
  VSS107  = GND
  DQ3_B  = M_I_CPU0_SB_DQ<3>
  VSS108  = GND
  \dqs5_b_c||tdqs5_b_c\  = M_I_CPU0_SB_DQS_DN<5>
  \dqs5_b_t||tdqs5_b_t\  = M_I_CPU0_SB_DQS_DP<5>
  VSS109  = GND
  DQ6_B  = M_I_CPU0_SB_DQ<6>
  VSS110  = GND
  DQ7_B  = M_I_CPU0_SB_DQ<7>
  VSS111  = GND
  DQ10_B  = M_I_CPU0_SB_DQ<10>
  VSS112  = GND
  DQ11_B  = M_I_CPU0_SB_DQ<11>
  VSS113  = GND
  \dqs6_b_c||tdqs6_b_c\  = M_I_CPU0_SB_DQS_DN<6>
  \dqs6_b_t||tdqs6_b_t\  = M_I_CPU0_SB_DQS_DP<6>
  VSS114  = GND
  DQ14_B  = M_I_CPU0_SB_DQ<14>
  VSS115  = GND
  DQ15_B  = M_I_CPU0_SB_DQ<15>
  VSS116  = GND
  DQ18_B  = M_I_CPU0_SB_DQ<18>
  VSS117  = GND
  DQ19_B  = M_I_CPU0_SB_DQ<19>
  VSS118  = GND
  \dqs7_b_c||tdqs7_b_c\  = M_I_CPU0_SB_DQS_DN<7>
  \dqs7_b_t||tdqs7_b_t\  = M_I_CPU0_SB_DQS_DP<7>
  VSS119  = GND
  DQ22_B  = M_I_CPU0_SB_DQ<22>
  VSS120  = GND
  DQ23_B  = M_I_CPU0_SB_DQ<23>
  VSS121  = GND
  DQ26_B  = M_I_CPU0_SB_DQ<26>
  VSS122  = GND
  DQ27_B  = M_I_CPU0_SB_DQ<27>
  VSS123  = GND
  \dqs8_b_c||tdqs8_b_c\  = M_I_CPU0_SB_DQS_DN<8>
  \dqs8_b_t||tdqs8_b_t\  = M_I_CPU0_SB_DQS_DP<8>
  VSS124  = GND
  DQ30_B  = M_I_CPU0_SB_DQ<30>
  VSS125  = GND
  DQ31_B  = M_I_CPU0_SB_DQ<31>
  VSS126  = GND
  G1  = GND
  G2  = GND
  G3  = GND

(kicad_pcb
	(version 20260206)
	(generator "pcbnew")
	(generator_version "10.0")
	(general
		(thickness 1.6)
		(legacy_teardrops no)
	)
	(paper "A4")
	(title_block
		(title "04192023_DAF0TMB3IC0_F0TG_MB_C_brd_V02_OCP.brd")
		(comment 1 "Grand Teton / footprint 4761 of 8354 (J18), pads 185-230 of 291")
	)
	(layers
		(0 "F.Cu" signal "TOP")
		(4 "In1.Cu" signal "GND")
		(6 "In2.Cu" signal "IN1")
		(8 "In3.Cu" signal "GND1")
		(10 "In4.Cu" signal "IN2")
		(12 "In5.Cu" signal "GND2")
		(14 "In6.Cu" signal "IN3")
		(16 "In7.Cu" signal "GND3")
		(18 "In8.Cu" signal "VCC")
		(20 "In9.Cu" signal "VCC1")
		(22 "In10.Cu" signal "GND4")
		(24 "In11.Cu" signal "IN4")
		(26 "In12.Cu" signal "GND5")
		(28 "In13.Cu" signal "IN5")
		(30 "In14.Cu" signal "GND6")
		(32 "In15.Cu" signal "IN6")
		(34 "In16.Cu" signal "GND7")
		(2 "B.Cu" signal "BOTTOM")
		(9 "F.Adhes" user "F.Adhesive")
		(11 "B.Adhes" user "B.Adhesive")
		(13 "F.Paste" user "Package Geometry/Pastemask Top")
		(15 "B.Paste" user "Package Geometry/Pastemask Bottom")
		(5 "F.SilkS" user "Ref Des/Silkscreen Top")
		(7 "B.SilkS" user "Ref Des/Silkscreen Bottom")
		(1 "F.Mask" user "Board Geometry/Soldermask Top")
		(3 "B.Mask" user "Board Geometry/Soldermask Bottom")
		(17 "Dwgs.User" user "User.Drawings")
		(19 "Cmts.User" user "User.Comments")
		(21 "Eco1.User" user "User.Eco1")
		(23 "Eco2.User" user "User.Eco2")
		(25 "Edge.Cuts" user "Board Geometry/Outline")
		(27 "Margin" user)
		(31 "F.CrtYd" user "Package Geometry/Place Bound Top")
		(29 "B.CrtYd" user "Package Geometry/Place Bound Bottom")
		(35 "F.Fab" user "Ref Des/Assembly Top")
		(33 "B.Fab" user "Ref Des/Assembly Bottom")
	)
	(footprint ""
		(layer "F.Cu")
		(at 429.506126 -255.560068 180)
		(property "Reference" "J18"
			(at 0.484632 -81.752948 0)
			(unlocked yes)
			(layer "F.SilkS")
			(effects
				(font
					(size 0.7874 0.5842)
					(thickness 0.1524)
				)
			)
		)
		(property "Value" ""
			(at 0 0 180)
			(layer "F.Fab")
			(effects
				(font
					(size 1.27 1.27)
				)
			)
		)
		(duplicate_pad_numbers_are_jumpers no)
		(pad "185" smd rect
			(at 2.050034 -29.325062 90)
			(size 0.519938 1.4986)
			(layers "F.Cu" "F.Mask" "F.Paste")
			(net "M_I_CPU0_SA_DQ<26>")
		)
		(pad "186" smd rect
			(at 2.050034 -28.474924 90)
			(size 0.519938 1.4986)
			(layers "F.Cu" "F.Mask" "F.Paste")
			(net "GND")
		)
		(pad "187" smd rect
			(at 2.050034 -27.62504 90)
			(size 0.519938 1.4986)
			(layers "F.Cu" "F.Mask" "F.Paste")
			(net "M_I_CPU0_SA_DQ<27>")
		)
		(pad "188" smd rect
			(at 2.050034 -26.774902 90)
			(size 0.519938 1.4986)
			(layers "F.Cu" "F.Mask" "F.Paste")
			(net "GND")
		)
		(pad "189" smd rect
			(at 2.050034 -25.925018 90)
			(size 0.519938 1.4986)
			(layers "F.Cu" "F.Mask" "F.Paste")
			(net "M_I_CPU0_SA_DQS_DN<8>")
		)
		(pad "190" smd rect
			(at 2.050034 -25.07488 90)
			(size 0.519938 1.4986)
			(layers "F.Cu" "F.Mask" "F.Paste")
			(net "M_I_CPU0_SA_DQS_DP<8>")
		)
		(pad "191" smd rect
			(at 2.050034 -24.224996 90)
			(size 0.519938 1.4986)
			(layers "F.Cu" "F.Mask" "F.Paste")
			(net "GND")
		)
		(pad "192" smd rect
			(at 2.050034 -23.375112 90)
			(size 0.519938 1.4986)
			(layers "F.Cu" "F.Mask" "F.Paste")
			(net "M_I_CPU0_SA_DQ<30>")
		)
		(pad "193" smd rect
			(at 2.050034 -22.524974 90)
			(size 0.519938 1.4986)
			(layers "F.Cu" "F.Mask" "F.Paste")
			(net "GND")
		)
		(pad "194" smd rect
			(at 2.050034 -21.67509 90)
			(size 0.519938 1.4986)
			(layers "F.Cu" "F.Mask" "F.Paste")
			(net "M_I_CPU0_SA_DQ<31>")
		)
		(pad "195" smd rect
			(at 2.050034 -20.824952 90)
			(size 0.519938 1.4986)
			(layers "F.Cu" "F.Mask" "F.Paste")
			(net "GND")
		)
		(pad "196" smd rect
			(at 2.050034 -19.975068 90)
			(size 0.519938 1.4986)
			(layers "F.Cu" "F.Mask" "F.Paste")
			(net "M_I_CPU0_SA_CB<2>")
		)
		(pad "197" smd rect
			(at 2.050034 -19.12493 90)
			(size 0.519938 1.4986)
			(layers "F.Cu" "F.Mask" "F.Paste")
			(net "GND")
		)
		(pad "198" smd rect
			(at 2.050034 -18.275046 90)
			(size 0.519938 1.4986)
			(layers "F.Cu" "F.Mask" "F.Paste")
			(net "M_I_CPU0_SA_CB<3>")
		)
		(pad "199" smd rect
			(at 2.050034 -17.424908 90)
			(size 0.519938 1.4986)
			(layers "F.Cu" "F.Mask" "F.Paste")
			(net "GND")
		)
		(pad "200" smd rect
			(at 2.050034 -16.575024 90)
			(size 0.519938 1.4986)
			(layers "F.Cu" "F.Mask" "F.Paste")
			(net "M_I_CPU0_SA_DQS_DN<9>")
		)
		(pad "201" smd rect
			(at 2.050034 -15.724886 90)
			(size 0.519938 1.4986)
			(layers "F.Cu" "F.Mask" "F.Paste")
			(net "M_I_CPU0_SA_DQS_DP<9>")
		)
		(pad "202" smd rect
			(at 2.050034 -14.875002 90)
			(size 0.519938 1.4986)
			(layers "F.Cu" "F.Mask" "F.Paste")
			(net "GND")
		)
		(pad "203" smd rect
			(at 2.050034 -14.025118 90)
			(size 0.519938 1.4986)
			(layers "F.Cu" "F.Mask" "F.Paste")
			(net "M_I_CPU0_SA_CB<6>")
		)
		(pad "204" smd rect
			(at 2.050034 -13.17498 90)
			(size 0.519938 1.4986)
			(layers "F.Cu" "F.Mask" "F.Paste")
			(net "GND")
		)
		(pad "205" smd rect
			(at 2.050034 -12.325096 90)
			(size 0.519938 1.4986)
			(layers "F.Cu" "F.Mask" "F.Paste")
			(net "M_I_CPU0_SA_CB<7>")
		)
		(pad "206" smd rect
			(at 2.050034 -11.474958 90)
			(size 0.519938 1.4986)
			(layers "F.Cu" "F.Mask" "F.Paste")
			(net "GND")
		)
		(pad "207" smd rect
			(at 2.050034 -10.625074 90)
			(size 0.519938 1.4986)
			(layers "F.Cu" "F.Mask" "F.Paste")
			(net "M_I_CPU0_RESET_N")
		)
		(pad "208" smd rect
			(at 2.050034 -9.774936 90)
			(size 0.519938 1.4986)
			(layers "F.Cu" "F.Mask" "F.Paste")
			(net "GND")
		)
		(pad "209" smd rect
			(at 2.050034 -8.925052 90)
			(size 0.519938 1.4986)
			(layers "F.Cu" "F.Mask" "F.Paste")
			(net "M_I_CPU0_SA_CS_N<1>")
		)
		(pad "210" smd rect
			(at 2.050034 -8.074914 90)
			(size 0.519938 1.4986)
			(layers "F.Cu" "F.Mask" "F.Paste")
			(net "GND")
		)
		(pad "211" smd rect
			(at 2.050034 -7.22503 90)
			(size 0.519938 1.4986)
			(layers "F.Cu" "F.Mask" "F.Paste")
			(net "M_I_CPU0_SA_CA<1>")
		)
		(pad "212" smd rect
			(at 2.050034 -6.374892 90)
			(size 0.519938 1.4986)
			(layers "F.Cu" "F.Mask" "F.Paste")
			(net "GND")
		)
		(pad "213" smd rect
			(at 2.050034 -5.525008 90)
			(size 0.519938 1.4986)
			(layers "F.Cu" "F.Mask" "F.Paste")
			(net "M_I_CPU0_SA_CA<3>")
		)
		(pad "214" smd rect
			(at 2.050034 -4.675124 90)
			(size 0.519938 1.4986)
			(layers "F.Cu" "F.Mask" "F.Paste")
			(net "GND")
		)
		(pad "215" smd rect
			(at 2.050034 -3.824986 90)
			(size 0.519938 1.4986)
			(layers "F.Cu" "F.Mask" "F.Paste")
			(net "M_I_CPU0_SA_CA<5>")
		)
		(pad "216" smd rect
			(at 2.050034 -2.975102 90)
			(size 0.519938 1.4986)
			(layers "F.Cu" "F.Mask" "F.Paste")
			(net "GND")
		)
		(pad "217" smd rect
			(at 2.050034 -2.124964 90)
			(size 0.519938 1.4986)
			(layers "F.Cu" "F.Mask" "F.Paste")
			(net "M_I_CPU0_CLK_DP<0>")
		)
		(pad "218" smd rect
			(at 2.050034 -1.27508 90)
			(size 0.519938 1.4986)
			(layers "F.Cu" "F.Mask" "F.Paste")
			(net "M_I_CPU0_CLK_DN<0>")
		)
		(pad "219" smd rect
			(at 2.050034 -0.424942 90)
			(size 0.519938 1.4986)
			(layers "F.Cu" "F.Mask" "F.Paste")
			(net "GND")
		)
		(pad "220" smd rect
			(at 2.050034 5.525008 90)
			(size 0.519938 1.4986)
			(layers "F.Cu" "F.Mask" "F.Paste")
			(net "Net_2365")
		)
		(pad "221" smd rect
			(at 2.050034 6.374892 90)
			(size 0.519938 1.4986)
			(layers "F.Cu" "F.Mask" "F.Paste")
			(net "M_I_CPU0_SB_CA<1>")
		)
		(pad "222" smd rect
			(at 2.050034 7.22503 90)
			(size 0.519938 1.4986)
			(layers "F.Cu" "F.Mask" "F.Paste")
			(net "GND")
		)
		(pad "223" smd rect
			(at 2.050034 8.074914 90)
			(size 0.519938 1.4986)
			(layers "F.Cu" "F.Mask" "F.Paste")
			(net "M_I_CPU0_SB_CA<3>")
		)
		(pad "224" smd rect
			(at 2.050034 8.925052 90)
			(size 0.519938 1.4986)
			(layers "F.Cu" "F.Mask" "F.Paste")
			(net "GND")
		)
		(pad "225" smd rect
			(at 2.050034 9.774936 90)
			(size 0.519938 1.4986)
			(layers "F.Cu" "F.Mask" "F.Paste")
			(net "M_I_CPU0_SB_CA<5>")
		)
		(pad "226" smd rect
			(at 2.050034 10.625074 90)
			(size 0.519938 1.4986)
			(layers "F.Cu" "F.Mask" "F.Paste")
			(net "GND")
		)
		(pad "227" smd rect
			(at 2.050034 11.474958 90)
			(size 0.519938 1.4986)
			(layers "F.Cu" "F.Mask" "F.Paste")
			(net "M_I_CPU0_SB_PAR")
		)
		(pad "228" smd rect
			(at 2.050034 12.325096 90)
			(size 0.519938 1.4986)
			(layers "F.Cu" "F.Mask" "F.Paste")
			(net "GND")
		)
		(pad "229" smd rect
			(at 2.050034 13.17498 90)
			(size 0.519938 1.4986)
			(layers "F.Cu" "F.Mask" "F.Paste")
			(net "M_I_CPU0_SB_CS_N<1>")
		)
		(pad "230" smd rect
			(at 2.050034 14.025118 90)
			(size 0.519938 1.4986)
			(layers "F.Cu" "F.Mask" "F.Paste")
			(net "GND")
		)
	)
)
